(kicad_pcb
	(version 20260206)
	(generator "pcbnew")
	(generator_version "10.0")
	(general
		(thickness 1.6)
		(legacy_teardrops no)
	)
	(paper "A4")
	(title_block
		(title "fcb — Lightning_FCB_BRD.brd")
		(comment 1 "Lightning (Wiwynn / Facebook NVMe JBOF) / footprints 188-195 of 495")
	)
	(layers
		(0 "F.Cu" signal "TOP")
		(4 "In1.Cu" signal "L2GND")
		(6 "In2.Cu" signal "L3VCC")
		(2 "B.Cu" signal "BOTTOM")
		(9 "F.Adhes" user "F.Adhesive")
		(11 "B.Adhes" user "B.Adhesive")
		(13 "F.Paste" user "Package Geometry/Pastemask Top")
		(15 "B.Paste" user "Package Geometry/Pastemask Bottom")
		(5 "F.SilkS" user "Ref Des/Silkscreen Top")
		(7 "B.SilkS" user "Ref Des/Silkscreen Bottom")
		(1 "F.Mask" user "Board Geometry/Soldermask Top")
		(3 "B.Mask" user "Board Geometry/Soldermask Bottom")
		(17 "Dwgs.User" user "User.Drawings")
		(19 "Cmts.User" user "User.Comments")
		(21 "Eco1.User" user "User.Eco1")
		(23 "Eco2.User" user "User.Eco2")
		(25 "Edge.Cuts" user "Board Geometry/Outline")
		(27 "Margin" user)
		(31 "F.CrtYd" user "Package Geometry/Place Bound Top")
		(29 "B.CrtYd" user "Package Geometry/Place Bound Bottom")
		(35 "F.Fab" user "Ref Des/Assembly Top")
		(33 "B.Fab" user "Ref Des/Assembly Bottom")
	)
	(footprint ""
		(layer "F.Cu")
		(at 41.4274 -135.1534 -90)
		(property "Reference" "PR100"
			(at 0 0 270)
			(layer "F.SilkS")
			(hide yes)
			(effects
				(font
					(size 1.27 1.27)
				)
			)
		)
		(property "Value" "1MR3J-L-GP"
			(at -0.0254 -2.5146 270)
			(unlocked yes)
			(layer "F.Fab")
			(hide yes)
			(effects
				(font
					(size 1.016 1.016)
					(thickness 0.1524)
				)
			)
		)
		(property "Device Type" "R603H22"
			(at -0.0254 -4.0386 270)
			(unlocked yes)
			(layer "F.Fab")
			(hide yes)
			(effects
				(font
					(size 1.016 1.016)
					(thickness 0.1524)
				)
			)
		)
		(duplicate_pad_numbers_are_jumpers no)
		(fp_line
			(start -0.4826 0)
			(end -0.2032 0)
			(stroke
				(width 0.2032)
				(type default)
			)
			(layer "F.SilkS")
		)
		(fp_line
			(start 0.2032 0)
			(end 0.4826 0)
			(stroke
				(width 0.2032)
				(type default)
			)
			(layer "F.SilkS")
		)
		(fp_rect
			(start -0.5842 1.3335)
			(end 0.5842 -1.3335)
			(stroke
				(width 0)
				(type default)
			)
			(fill no)
			(layer "F.CrtYd")
		)
		(fp_rect
			(start -0.5842 1.3335)
			(end 0.5842 -1.3335)
			(stroke
				(width 0)
				(type default)
			)
			(fill no)
			(layer "F.Fab")
		)
		(pad "1" smd custom
			(at 0 -0.762 270)
			(size 0.2159 0.2159)
			(layers "F.Cu" "F.Mask" "F.Paste")
			(net "P12VL_2490_VCC")
			(options
				(clearance outline)
				(anchor circle)
			)
			(primitives
				(gr_poly
					(pts
						(arc
							(start -0.3302 -0.4318)
							(mid -0.402042 -0.402042)
							(end -0.4318 -0.3302)
						)
						(arc
							(start -0.4318 0.3302)
							(mid -0.402042 0.402042)
							(end -0.3302 0.4318)
						)
						(arc
							(start 0.3302 0.4318)
							(mid 0.402042 0.402042)
							(end 0.4318 0.3302)
						)
						(arc
							(start 0.4318 -0.3302)
							(mid 0.402042 -0.402042)
							(end 0.3302 -0.4318)
						)
					)
					(width 0)
					(fill yes)
				)
			)
		)
		(pad "2" smd custom
			(at 0 0.762 270)
			(size 0.2159 0.2159)
			(layers "F.Cu" "F.Mask" "F.Paste")
			(net "P12VL_2490_SENSE")
			(options
				(clearance outline)
				(anchor circle)
			)
			(primitives
				(gr_poly
					(pts
						(arc
							(start -0.3302 -0.4318)
							(mid -0.402042 -0.402042)
							(end -0.4318 -0.3302)
						)
						(arc
							(start -0.4318 0.3302)
							(mid -0.402042 0.402042)
							(end -0.3302 0.4318)
						)
						(arc
							(start 0.3302 0.4318)
							(mid 0.402042 0.402042)
							(end 0.4318 0.3302)
						)
						(arc
							(start 0.4318 -0.3302)
							(mid 0.402042 -0.402042)
							(end 0.3302 -0.4318)
						)
					)
					(width 0)
					(fill yes)
				)
			)
		)
	)
	(footprint ""
		(layer "F.Cu")
		(at 18.288 -122.555)
		(property "Reference" "PR60"
			(at 0 0 0)
			(layer "F.SilkS")
			(hide yes)
			(effects
				(font
					(size 1.27 1.27)
				)
			)
		)
		(property "Value" "D002R2512F-GP"
			(at -3.228594 -1.194054 0)
			(unlocked yes)
			(layer "F.Fab")
			(hide yes)
			(effects
				(font
					(size 1.016 1.016)
					(thickness 0.1524)
				)
			)
		)
		(property "Device Type" "R2512-2H32"
			(at -3.228594 -2.718054 0)
			(unlocked yes)
			(layer "F.Fab")
			(hide yes)
			(effects
				(font
					(size 1.016 1.016)
					(thickness 0.1524)
				)
			)
		)
		(duplicate_pad_numbers_are_jumpers no)
		(fp_line
			(start -1.9685 -3.81)
			(end 1.9685 -3.81)
			(stroke
				(width 0.1524)
				(type default)
			)
			(layer "F.SilkS")
		)
		(fp_line
			(start -1.9685 3.81)
			(end -1.9685 -3.81)
			(stroke
				(width 0.1524)
				(type default)
			)
			(layer "F.SilkS")
		)
		(fp_line
			(start 1.9685 -3.81)
			(end 1.9685 3.81)
			(stroke
				(width 0.1524)
				(type default)
			)
			(layer "F.SilkS")
		)
		(fp_line
			(start 1.9685 3.81)
			(end -1.9685 3.81)
			(stroke
				(width 0.1524)
				(type default)
			)
			(layer "F.SilkS")
		)
		(fp_rect
			(start -1.5875 3.175)
			(end 1.5875 -3.175)
			(stroke
				(width 0)
				(type default)
			)
			(fill no)
			(layer "F.CrtYd")
		)
		(fp_poly
			(pts
				(xy -2.2225 3.8862) (xy -2.2225 0.00254) (xy -1.5875 0.00254) (xy -1.5875 3.175) (xy 1.5875 3.175)
				(xy 1.5875 -3.175) (xy -1.5875 -3.175) (xy -1.5875 -0.00254) (xy -2.2225 -0.00254) (xy -2.2225 -3.8862)
				(xy 2.2225 -3.8862) (xy 2.2225 3.8862)
			)
			(stroke
				(width 0)
				(type default)
			)
			(fill no)
			(layer "F.CrtYd")
		)
		(fp_rect
			(start -2.2225 3.8862)
			(end 2.2225 -3.8862)
			(stroke
				(width 0)
				(type default)
			)
			(fill no)
			(layer "F.Fab")
		)
		(pad "1" smd rect
			(at 0 -2.273808)
			(size 3.429 2.5654)
			(layers "F.Cu" "F.Mask" "F.Paste")
			(net "P12V")
		)
		(pad "2" smd rect
			(at 0 2.273808)
			(size 3.429 2.5654)
			(layers "F.Cu" "F.Mask" "F.Paste")
			(net "P12VU_NET")
		)
	)
	(footprint ""
		(layer "F.Cu")
		(at 21.6916 -144.7546 -90)
		(property "Reference" "PR110"
			(at 0 0 270)
			(layer "F.SilkS")
			(hide yes)
			(effects
				(font
					(size 1.27 1.27)
				)
			)
		)
		(property "Value" "178KR2F-GP"
			(at 0.064008 -3.993896 270)
			(unlocked yes)
			(layer "F.Fab")
			(hide yes)
			(effects
				(font
					(size 1.016 1.016)
					(thickness 0.1524)
				)
			)
		)
		(property "Device Type" "R402H16"
			(at 0.064008 -5.517896 270)
			(unlocked yes)
			(layer "F.Fab")
			(hide yes)
			(effects
				(font
					(size 1.016 1.016)
					(thickness 0.1524)
				)
			)
		)
		(duplicate_pad_numbers_are_jumpers no)
		(fp_line
			(start -0.508 -0.9398)
			(end -0.508 0.9398)
			(stroke
				(width 0.1524)
				(type default)
			)
			(layer "F.SilkS")
		)
		(fp_line
			(start 0.508 -0.9398)
			(end -0.508 -0.9398)
			(stroke
				(width 0.1524)
				(type default)
			)
			(layer "F.SilkS")
		)
		(fp_rect
			(start -0.508 0.9398)
			(end 0.508 -0.9398)
			(stroke
				(width 0)
				(type default)
			)
			(fill no)
			(layer "F.CrtYd")
		)
		(fp_rect
			(start -0.508 0.9398)
			(end 0.508 -0.9398)
			(stroke
				(width 0)
				(type default)
			)
			(fill no)
			(layer "F.Fab")
		)
		(pad "1" smd custom
			(at 0 -0.4445 270)
			(size 0.1397 0.1397)
			(layers "F.Cu" "F.Mask" "F.Paste")
			(net "P12VU_2490_VREF")
			(options
				(clearance outline)
				(anchor circle)
			)
			(primitives
				(gr_poly
					(pts
						(arc
							(start -0.1778 -0.2794)
							(mid -0.249642 -0.249642)
							(end -0.2794 -0.1778)
						)
						(arc
							(start -0.2794 0.1778)
							(mid -0.249642 0.249642)
							(end -0.1778 0.2794)
						)
						(arc
							(start 0.1778 0.2794)
							(mid 0.249642 0.249642)
							(end 0.2794 0.1778)
						)
						(arc
							(start 0.2794 -0.1778)
							(mid 0.249642 -0.249642)
							(end 0.1778 -0.2794)
						)
					)
					(width 0)
					(fill yes)
				)
			)
		)
		(pad "2" smd custom
			(at 0 0.4445 270)
			(size 0.1397 0.1397)
			(layers "F.Cu" "F.Mask" "F.Paste")
			(net "P12VU_2490_PROG")
			(options
				(clearance outline)
				(anchor circle)
			)
			(primitives
				(gr_poly
					(pts
						(arc
							(start -0.1778 -0.2794)
							(mid -0.249642 -0.249642)
							(end -0.2794 -0.1778)
						)
						(arc
							(start -0.2794 0.1778)
							(mid -0.249642 0.249642)
							(end -0.1778 0.2794)
						)
						(arc
							(start 0.1778 0.2794)
							(mid 0.249642 0.249642)
							(end 0.2794 0.1778)
						)
						(arc
							(start 0.2794 -0.1778)
							(mid 0.249642 -0.249642)
							(end 0.1778 -0.2794)
						)
					)
					(width 0)
					(fill yes)
				)
			)
		)
	)
	(footprint ""
		(layer "F.Cu")
		(at 14.8844 -40.4622 90)
		(property "Reference" "R172"
			(at 0 0 90)
			(layer "F.SilkS")
			(hide yes)
			(effects
				(font
					(size 1.27 1.27)
				)
			)
		)
		(property "Value" "0R2J-2-GP"
			(at 0.064008 -3.993896 90)
			(unlocked yes)
			(layer "F.Fab")
			(hide yes)
			(effects
				(font
					(size 1.016 1.016)
					(thickness 0.1524)
				)
			)
		)
		(property "Device Type" "R402H16"
			(at 0.064008 -5.517896 90)
			(unlocked yes)
			(layer "F.Fab")
			(hide yes)
			(effects
				(font
					(size 1.016 1.016)
					(thickness 0.1524)
				)
			)
		)
		(duplicate_pad_numbers_are_jumpers no)
		(fp_line
			(start 0.508 -0.9398)
			(end -0.508 -0.9398)
			(stroke
				(width 0.1524)
				(type default)
			)
			(layer "F.SilkS")
		)
		(fp_line
			(start -0.508 -0.9398)
			(end -0.508 0.9398)
			(stroke
				(width 0.1524)
				(type default)
			)
			(layer "F.SilkS")
		)
		(fp_rect
			(start -0.508 0.9398)
			(end 0.508 -0.9398)
			(stroke
				(width 0)
				(type default)
			)
			(fill no)
			(layer "F.CrtYd")
		)
		(fp_rect
			(start -0.508 0.9398)
			(end 0.508 -0.9398)
			(stroke
				(width 0)
				(type default)
			)
			(fill no)
			(layer "F.Fab")
		)
		(pad "1" smd custom
			(at 0 -0.4445 90)
			(size 0.1397 0.1397)
			(layers "F.Cu" "F.Mask" "F.Paste")
			(net "SELF_1B_HB")
			(options
				(clearance outline)
				(anchor circle)
			)
			(primitives
				(gr_poly
					(pts
						(arc
							(start -0.1778 -0.2794)
							(mid -0.249642 -0.249642)
							(end -0.2794 -0.1778)
						)
						(arc
							(start -0.2794 0.1778)
							(mid -0.249642 0.249642)
							(end -0.1778 0.2794)
						)
						(arc
							(start 0.1778 0.2794)
							(mid 0.249642 0.249642)
							(end 0.2794 0.1778)
						)
						(arc
							(start 0.2794 -0.1778)
							(mid 0.249642 -0.249642)
							(end 0.1778 -0.2794)
						)
					)
					(width 0)
					(fill yes)
				)
			)
		)
		(pad "2" smd custom
			(at 0 0.4445 90)
			(size 0.1397 0.1397)
			(layers "F.Cu" "F.Mask" "F.Paste")
			(net "SEB_PEER_2B_HB")
			(options
				(clearance outline)
				(anchor circle)
			)
			(primitives
				(gr_poly
					(pts
						(arc
							(start -0.1778 -0.2794)
							(mid -0.249642 -0.249642)
							(end -0.2794 -0.1778)
						)
						(arc
							(start -0.2794 0.1778)
							(mid -0.249642 0.249642)
							(end -0.1778 0.2794)
						)
						(arc
							(start 0.1778 0.2794)
							(mid 0.249642 0.249642)
							(end 0.2794 0.1778)
						)
						(arc
							(start 0.2794 -0.1778)
							(mid 0.249642 -0.249642)
							(end 0.1778 -0.2794)
						)
					)
					(width 0)
					(fill yes)
				)
			)
		)
	)
	(footprint ""
		(layer "F.Cu")
		(at 15.9004 -62.865 180)
		(property "Reference" "R61"
			(at 0 0 180)
			(layer "F.SilkS")
			(hide yes)
			(effects
				(font
					(size 1.27 1.27)
				)
			)
		)
		(property "Value" "4K7R2F-GP"
			(at 0.064008 -3.993896 180)
			(unlocked yes)
			(layer "F.Fab")
			(hide yes)
			(effects
				(font
					(size 1.016 1.016)
					(thickness 0.1524)
				)
			)
		)
		(property "Device Type" "R402H16"
			(at 0.064008 -5.517896 180)
			(unlocked yes)
			(layer "F.Fab")
			(hide yes)
			(effects
				(font
					(size 1.016 1.016)
					(thickness 0.1524)
				)
			)
		)
		(duplicate_pad_numbers_are_jumpers no)
		(fp_line
			(start 0.508 -0.9398)
			(end -0.508 -0.9398)
			(stroke
				(width 0.1524)
				(type default)
			)
			(layer "F.SilkS")
		)
		(fp_line
			(start -0.508 -0.9398)
			(end -0.508 0.9398)
			(stroke
				(width 0.1524)
				(type default)
			)
			(layer "F.SilkS")
		)
		(fp_rect
			(start -0.508 0.9398)
			(end 0.508 -0.9398)
			(stroke
				(width 0)
				(type default)
			)
			(fill no)
			(layer "F.CrtYd")
		)
		(fp_rect
			(start -0.508 0.9398)
			(end 0.508 -0.9398)
			(stroke
				(width 0)
				(type default)
			)
			(fill no)
			(layer "F.Fab")
		)
		(pad "1" smd custom
			(at 0 -0.4445 180)
			(size 0.1397 0.1397)
			(layers "F.Cu" "F.Mask" "F.Paste")
			(net "P3V3")
			(options
				(clearance outline)
				(anchor circle)
			)
			(primitives
				(gr_poly
					(pts
						(arc
							(start -0.1778 -0.2794)
							(mid -0.249642 -0.249642)
							(end -0.2794 -0.1778)
						)
						(arc
							(start -0.2794 0.1778)
							(mid -0.249642 0.249642)
							(end -0.1778 0.2794)
						)
						(arc
							(start 0.1778 0.2794)
							(mid 0.249642 0.249642)
							(end 0.2794 0.1778)
						)
						(arc
							(start 0.2794 -0.1778)
							(mid 0.249642 -0.249642)
							(end 0.1778 -0.2794)
						)
					)
					(width 0)
					(fill yes)
				)
			)
		)
		(pad "2" smd custom
			(at 0 0.4445 180)
			(size 0.1397 0.1397)
			(layers "F.Cu" "F.Mask" "F.Paste")
			(net "I2C_C_SCL_CONN_R")
			(options
				(clearance outline)
				(anchor circle)
			)
			(primitives
				(gr_poly
					(pts
						(arc
							(start -0.1778 -0.2794)
							(mid -0.249642 -0.249642)
							(end -0.2794 -0.1778)
						)
						(arc
							(start -0.2794 0.1778)
							(mid -0.249642 0.249642)
							(end -0.1778 0.2794)
						)
						(arc
							(start 0.1778 0.2794)
							(mid 0.249642 0.249642)
							(end 0.2794 0.1778)
						)
						(arc
							(start 0.2794 -0.1778)
							(mid 0.249642 -0.249642)
							(end 0.1778 -0.2794)
						)
					)
					(width 0)
					(fill yes)
				)
			)
		)
	)
	(footprint ""
		(layer "F.Cu")
		(at 36.0426 -369.1382 -90)
		(property "Reference" "PR4"
			(at 0 0 270)
			(layer "F.SilkS")
			(hide yes)
			(effects
				(font
					(size 1.27 1.27)
				)
			)
		)
		(property "Value" "49K9R2F-L-GP"
			(at 0.064008 -3.993896 270)
			(unlocked yes)
			(layer "F.Fab")
			(hide yes)
			(effects
				(font
					(size 1.016 1.016)
					(thickness 0.1524)
				)
			)
		)
		(property "Device Type" "R402H16"
			(at 0.064008 -5.517896 270)
			(unlocked yes)
			(layer "F.Fab")
			(hide yes)
			(effects
				(font
					(size 1.016 1.016)
					(thickness 0.1524)
				)
			)
		)
		(duplicate_pad_numbers_are_jumpers no)
		(fp_line
			(start -0.508 -0.9398)
			(end -0.508 0.9398)
			(stroke
				(width 0.1524)
				(type default)
			)
			(layer "F.SilkS")
		)
		(fp_line
			(start 0.508 -0.9398)
			(end -0.508 -0.9398)
			(stroke
				(width 0.1524)
				(type default)
			)
			(layer "F.SilkS")
		)
		(fp_rect
			(start -0.508 0.9398)
			(end 0.508 -0.9398)
			(stroke
				(width 0)
				(type default)
			)
			(fill no)
			(layer "F.CrtYd")
		)
		(fp_rect
			(start -0.508 0.9398)
			(end 0.508 -0.9398)
			(stroke
				(width 0)
				(type default)
			)
			(fill no)
			(layer "F.Fab")
		)
		(pad "1" smd custom
			(at 0 -0.4445 270)
			(size 0.1397 0.1397)
			(layers "F.Cu" "F.Mask" "F.Paste")
			(net "P12V_AUX")
			(options
				(clearance outline)
				(anchor circle)
			)
			(primitives
				(gr_poly
					(pts
						(arc
							(start -0.1778 -0.2794)
							(mid -0.249642 -0.249642)
							(end -0.2794 -0.1778)
						)
						(arc
							(start -0.2794 0.1778)
							(mid -0.249642 0.249642)
							(end -0.1778 0.2794)
						)
						(arc
							(start 0.1778 0.2794)
							(mid 0.249642 0.249642)
							(end 0.2794 0.1778)
						)
						(arc
							(start 0.2794 -0.1778)
							(mid 0.249642 -0.249642)
							(end 0.1778 -0.2794)
						)
					)
					(width 0)
					(fill yes)
				)
			)
		)
		(pad "2" smd custom
			(at 0 0.4445 270)
			(size 0.1397 0.1397)
			(layers "F.Cu" "F.Mask" "F.Paste")
			(net "ADM1276_PWRGD")
			(options
				(clearance outline)
				(anchor circle)
			)
			(primitives
				(gr_poly
					(pts
						(arc
							(start -0.1778 -0.2794)
							(mid -0.249642 -0.249642)
							(end -0.2794 -0.1778)
						)
						(arc
							(start -0.2794 0.1778)
							(mid -0.249642 0.249642)
							(end -0.1778 0.2794)
						)
						(arc
							(start 0.1778 0.2794)
							(mid 0.249642 0.249642)
							(end 0.2794 0.1778)
						)
						(arc
							(start 0.2794 -0.1778)
							(mid 0.249642 -0.249642)
							(end 0.1778 -0.2794)
						)
					)
					(width 0)
					(fill yes)
				)
			)
		)
	)
	(footprint ""
		(layer "F.Cu")
		(at 14.5034 -248.1834)
		(property "Reference" "PR57"
			(at 0 0 0)
			(layer "F.SilkS")
			(hide yes)
			(effects
				(font
					(size 1.27 1.27)
				)
			)
		)
		(property "Value" "0R0603-PAD-2-GP"
			(at -0.0254 -2.3622 0)
			(unlocked yes)
			(layer "F.Fab")
			(hide yes)
			(effects
				(font
					(size 1.016 1.016)
					(thickness 0.1524)
				)
			)
		)
		(property "Device Type" "0R0603-PAD-1"
			(at -0.0254 -3.8862 0)
			(unlocked yes)
			(layer "F.Fab")
			(hide yes)
			(effects
				(font
					(size 1.016 1.016)
					(thickness 0.1524)
				)
			)
		)
		(duplicate_pad_numbers_are_jumpers no)
		(fp_line
			(start -0.6604 -1.3716)
			(end -0.6604 1.3716)
			(stroke
				(width 0.1524)
				(type default)
			)
			(layer "F.SilkS")
		)
		(fp_line
			(start 0.6604 -1.3716)
			(end -0.6604 -1.3716)
			(stroke
				(width 0.1524)
				(type default)
			)
			(layer "F.SilkS")
		)
		(fp_rect
			(start -0.6604 1.3716)
			(end 0.6604 -1.3716)
			(stroke
				(width 0)
				(type default)
			)
			(fill no)
			(layer "F.CrtYd")
		)
		(fp_rect
			(start -0.6604 1.3716)
			(end 0.6604 -1.3716)
			(stroke
				(width 0)
				(type default)
			)
			(fill no)
			(layer "F.Fab")
		)
		(pad "1" smd custom
			(at 0 -0.8509)
			(size 0.2159 0.2159)
			(layers "F.Cu" "F.Mask" "F.Paste")
			(net "P12V")
			(options
				(clearance outline)
				(anchor circle)
			)
			(primitives
				(gr_poly
					(pts
						(arc
							(start 0.4318 0.4826)
							(mid 0.402042 0.554442)
							(end 0.3302 0.5842)
						)
						(arc
							(start -0.3302 0.5842)
							(mid -0.402042 0.554442)
							(end -0.4318 0.4826)
						)
						(arc
							(start -0.4318 -0.4826)
							(mid -0.402042 -0.554442)
							(end -0.3302 -0.5842)
						)
						(arc
							(start 0.3302 -0.5842)
							(mid 0.402042 -0.554442)
							(end 0.4318 -0.4826)
						)
					)
					(width 0)
					(fill yes)
				)
			)
		)
		(pad "2" smd custom
			(at 0 0.6731)
			(size 0.2159 0.2159)
			(layers "F.Cu" "F.Mask" "F.Paste")
			(net "P3V3_IN")
			(options
				(clearance outline)
				(anchor circle)
			)
			(primitives
				(gr_poly
					(pts
						(arc
							(start -0.3302 0.5842)
							(mid -0.402042 0.554442)
							(end -0.4318 0.4826)
						)
						(arc
							(start -0.4318 -0.4826)
							(mid -0.402042 -0.554442)
							(end -0.3302 -0.5842)
						)
						(arc
							(start 0.3302 -0.5842)
							(mid 0.402042 -0.554442)
							(end 0.4318 -0.4826)
						)
						(arc
							(start 0.4318 0.4826)
							(mid 0.402042 0.554442)
							(end 0.3302 0.5842)
						)
					)
					(width 0)
					(fill yes)
				)
			)
		)
	)
	(footprint ""
		(layer "F.Cu")
		(at 40.8178 -156.4386 180)
		(property "Reference" "TP17"
			(at 0 0 180)
			(layer "F.SilkS")
			(hide yes)
			(effects
				(font
					(size 1.27 1.27)
				)
			)
		)
		(property "Value" "TPAD32-GP"
			(at 0 -3.166364 180)
			(unlocked yes)
			(layer "F.Fab")
			(hide yes)
			(effects
				(font
					(size 1.016 1.016)
					(thickness 0.1524)
				)
			)
		)
		(property "Device Type" "TPAD32"
			(at 0 -4.690618 180)
			(unlocked yes)
			(layer "F.Fab")
			(hide yes)
			(effects
				(font
					(size 1.016 1.016)
					(thickness 0.1524)
				)
			)
		)
		(duplicate_pad_numbers_are_jumpers no)
		(fp_poly
			(pts
				(arc
					(start -0.7112 0)
					(mid 0.7112 0)
					(end -0.7112 0)
				)
			)
			(stroke
				(width 0)
				(type default)
			)
			(fill no)
			(layer "F.CrtYd")
		)
		(fp_poly
			(pts
				(arc
					(start -0.7112 0)
					(mid 0.7112 0)
					(end -0.7112 0)
				)
			)
			(stroke
				(width 0)
				(type default)
			)
			(fill no)
			(layer "F.Fab")
		)
		(pad "1" smd circle
			(at 0 0 180)
			(size 0.8128 0.8128)
			(layers "F.Cu" "F.Mask" "F.Paste")
			(net "NCT7904_PROCHOT")
		)
	)
)
